FILE_TYPE = CONNECTIVITY;
{Allegro Design Entry HDL 17.4-2019 S026 (4007227) 1/17/2022}
"PAGE_NUMBER" = 447;
0"NC";
1"P5E_CPU1_P2_TX_C_DN<7:0>";
2"P5E_CPU1_P2_TX_C_DP<7:0>";
3"P5E_CPU1_P2_TX_C_DP<15:8>";
4"P5E_CPU1_P2_TX_C_DN<15:8>";
5"P5E_CPU1_P2_TX_C_DP<2>";
6"P5E_CPU1_P2_TX_C_DP<1>";
7"P5E_CPU1_P2_TX_C_DN<1>";
8"P5E_CPU1_P2_TX_C_DN<2>";
9"P5E_CPU1_P2_TX_C_DN<0>";
10"P5E_CPU1_P2_TX_C_DP<5>";
11"P5E_CPU1_P2_TX_C_DP<6>";
12"P5E_CPU1_P2_TX_C_DN<6>";
13"P5E_CPU1_P2_TX_C_DP<7>";
14"P5E_CPU1_P2_TX_C_DN<7>";
15"P5E_CPU1_P2_TX_C_DN<15>";
16"P5E_CPU1_P2_TX_C_DP<14>";
17"P5E_CPU1_P2_TX_C_DN<4>";
18"P5E_CPU1_P2_TX_C_DP<4>";
19"P5E_CPU1_P2_TX_C_DN<3>";
20"P5E_CPU1_P2_TX_C_DP<12>";
21"P5E_CPU1_P2_TX_C_DN<10>";
22"P5E_CPU1_P2_TX_C_DP<10>";
23"P5E_CPU1_P2_TX_C_DN<9>";
24"P5E_CPU1_P2_TX_C_DP<9>";
25"P5E_CPU1_P2_TX_C_DN<13>";
26"P5E_CPU1_P2_TX_C_DP<15>";
27"P5E_CPU1_P2_TX_C_DN<12>";
28"P5E_CPU1_P2_TX_C_DN<8>";
29"P5E_CPU1_P2_TX_C_DP<11>";
30"P5E_CPU1_P2_TX_C_DN<11>";
31"P5E_CPU1_P2_TX_C_DP<13>";
32"P5E_CPU1_P2_TX_C_DN<14>";
33"P5E_CPU1_P2_TX_C_DP<8>";
34"P5E_CPU1_P2_TX_C_DP<3>";
35"P5E_CPU1_P2_TX_C_DP<0>";
36"P5E_CPU1_P2_TX_C_DN<5>";
%"PT5161LRS"
"8","(-7575,3800)","0","pure_quanta","I1";
;
LOCATION"U6016"
$SEC"8"
CDS_SEC"8"
VALUE"PT5161LRS"
PART_TYPE"SMLF"
MATERIAL"IC"
NEEDS_NO_SIZE"TRUE"
CDS_LMAN_SYM_OUTLINE"-350,1450,300,-1400"
CDS_LIB"pure_quanta"
PART_NUMBER"AJ051610U03";
"B_PERN7"
$PN"CD35"33;
"B_PERP7"
$PN"CB34"28;
"B_PERN6"
$PN"BU35"24;
"B_PERP6"
$PN"BR34"23;
"B_PERN5"
$PN"BK35"22;
"B_PERP5"
$PN"BH34"21;
"B_PERN4"
$PN"BC35"29;
"B_PERP4"
$PN"BA34"30;
"B_PERN3"
$PN"AT35"20;
"B_PERP3"
$PN"AP34"27;
"B_PERN2"
$PN"AJ35"31;
"B_PERP2"
$PN"AG34"25;
"B_PERN1"
$PN"AB35"16;
"B_PERP1"
$PN"Y34"32;
"B_PERN0"
$PN"R35"26;
"B_PERP0"
$PN"N34"15;
%"TAP"
"1","(-6350,3900)","0","standard","I10";
;
CDS_LIB"standard"
BODY_TYPE"PLUMBING"
HDL_TAP"TRUE";
"B \NAC \NWC"3;
"S \NAC"
BN"12"20;
%"TAP"
"1","(-6550,4000)","0","standard","I11";
;
CDS_LIB"standard"
BODY_TYPE"PLUMBING"
HDL_TAP"TRUE";
"B \NAC \NWC"4;
"S \NAC"
BN"12"27;
%"TAP"
"1","(-6550,4350)","0","standard","I12";
;
CDS_LIB"standard"
BODY_TYPE"PLUMBING"
HDL_TAP"TRUE";
"B \NAC \NWC"4;
"S \NAC"
BN"13"25;
%"TAP"
"1","(-6550,4700)","0","standard","I13";
;
CDS_LIB"standard"
BODY_TYPE"PLUMBING"
HDL_TAP"TRUE";
"B \NAC \NWC"4;
"S \NAC"
BN"14"32;
%"TAP"
"1","(-6350,4250)","0","standard","I14";
;
CDS_LIB"standard"
BODY_TYPE"PLUMBING"
HDL_TAP"TRUE";
"B \NAC \NWC"3;
"S \NAC"
BN"13"31;
%"TAP"
"1","(-6350,4600)","0","standard","I15";
;
CDS_LIB"standard"
BODY_TYPE"PLUMBING"
HDL_TAP"TRUE";
"B \NAC \NWC"3;
"S \NAC"
BN"14"16;
%"TAP"
"1","(-6350,4950)","0","standard","I16";
;
CDS_LIB"standard"
BODY_TYPE"PLUMBING"
HDL_TAP"TRUE";
"B \NAC \NWC"3;
"S \NAC"
BN"15"26;
%"TAP"
"1","(-6550,5050)","0","standard","I17";
;
CDS_LIB"standard"
BODY_TYPE"PLUMBING"
HDL_TAP"TRUE";
"B \NAC \NWC"4;
"S \NAC"
BN"15"15;
%"TAP"
"1","(-6550,2600)","0","standard","I2";
;
CDS_LIB"standard"
BODY_TYPE"PLUMBING"
HDL_TAP"TRUE";
"B \NAC \NWC"4;
"S \NAC"
BN"8"28;
%"TAP"
"1","(-1925,2550)","0","standard","I20";
;
CDS_LIB"standard"
BODY_TYPE"PLUMBING"
HDL_TAP"TRUE";
"B \NAC \NWC"1;
"S \NAC"
BN"0"9;
%"TAP"
"1","(-1925,2800)","0","standard","I21";
;
CDS_LIB"standard"
BODY_TYPE"PLUMBING"
HDL_TAP"TRUE";
"B \NAC \NWC"1;
"S \NAC"
BN"1"7;
%"TAP"
"1","(-1925,3250)","0","standard","I22";
;
CDS_LIB"standard"
BODY_TYPE"PLUMBING"
HDL_TAP"TRUE";
"B \NAC \NWC"1;
"S \NAC"
BN"2"8;
%"TAP"
"1","(-1925,3600)","0","standard","I23";
;
CDS_LIB"standard"
BODY_TYPE"PLUMBING"
HDL_TAP"TRUE";
"B \NAC \NWC"1;
"S \NAC"
BN"3"19;
%"TAP"
"1","(-1725,2450)","0","standard","I24";
;
CDS_LIB"standard"
BODY_TYPE"PLUMBING"
HDL_TAP"TRUE";
"B \NAC \NWC"2;
"S \NAC"
BN"0"35;
%"TAP"
"1","(-1725,2900)","0","standard","I25";
;
CDS_LIB"standard"
BODY_TYPE"PLUMBING"
HDL_TAP"TRUE";
"B \NAC \NWC"2;
"S \NAC"
BN"1"6;
%"TAP"
"1","(-1725,3150)","0","standard","I26";
;
CDS_LIB"standard"
BODY_TYPE"PLUMBING"
HDL_TAP"TRUE";
"B \NAC \NWC"2;
"S \NAC"
BN"2"5;
%"TAP"
"1","(-1725,3500)","0","standard","I27";
;
CDS_LIB"standard"
BODY_TYPE"PLUMBING"
HDL_TAP"TRUE";
"B \NAC \NWC"2;
"S \NAC"
BN"3"34;
%"TAP"
"1","(-1725,3850)","0","standard","I28";
;
CDS_LIB"standard"
BODY_TYPE"PLUMBING"
HDL_TAP"TRUE";
"B \NAC \NWC"2;
"S \NAC"
BN"4"18;
%"TAP"
"1","(-1925,3950)","0","standard","I29";
;
CDS_LIB"standard"
BODY_TYPE"PLUMBING"
HDL_TAP"TRUE";
"B \NAC \NWC"1;
"S \NAC"
BN"4"17;
%"TAP"
"1","(-6350,2500)","0","standard","I3";
;
CDS_LIB"standard"
BODY_TYPE"PLUMBING"
HDL_TAP"TRUE";
"B \NAC \NWC"3;
"S \NAC"
BN"8"33;
%"TAP"
"1","(-1925,4300)","0","standard","I30";
;
CDS_LIB"standard"
BODY_TYPE"PLUMBING"
HDL_TAP"TRUE";
"B \NAC \NWC"1;
"S \NAC"
BN"5"36;
%"TAP"
"1","(-1925,4650)","0","standard","I31";
;
CDS_LIB"standard"
BODY_TYPE"PLUMBING"
HDL_TAP"TRUE";
"B \NAC \NWC"1;
"S \NAC"
BN"6"12;
%"TAP"
"1","(-1925,5000)","0","standard","I32";
;
CDS_LIB"standard"
BODY_TYPE"PLUMBING"
HDL_TAP"TRUE";
"B \NAC \NWC"1;
"S \NAC"
BN"7"14;
%"TAP"
"1","(-1725,4200)","0","standard","I33";
;
CDS_LIB"standard"
BODY_TYPE"PLUMBING"
HDL_TAP"TRUE";
"B \NAC \NWC"2;
"S \NAC"
BN"5"10;
%"TAP"
"1","(-1725,4550)","0","standard","I34";
;
CDS_LIB"standard"
BODY_TYPE"PLUMBING"
HDL_TAP"TRUE";
"B \NAC \NWC"2;
"S \NAC"
BN"6"11;
%"TAP"
"1","(-1725,4900)","0","standard","I35";
;
CDS_LIB"standard"
BODY_TYPE"PLUMBING"
HDL_TAP"TRUE";
"B \NAC \NWC"2;
"S \NAC"
BN"7"13;
%"PT5161LRS"
"9","(-2950,3750)","0","pure_quanta","I38";
;
LOCATION"U6016"
$SEC"9"
CDS_SEC"9"
MATERIAL"IC"
VALUE"PT5161LRS"
PART_TYPE"SMLF"
CDS_LIB"pure_quanta"
CDS_LMAN_SYM_OUTLINE"-350,1450,300,-1400"
NEEDS_NO_SIZE"TRUE"
PART_NUMBER"AJ051610U03";
"B_PERN15"
$PN"EY35"35;
"B_PERP15"
$PN"EV34"9;
"B_PERN14"
$PN"EN35"7;
"B_PERP14"
$PN"EL34"6;
"B_PERN13"
$PN"EF35"5;
"B_PERP13"
$PN"ED34"8;
"B_PERN12"
$PN"DW35"34;
"B_PERP12"
$PN"DU34"19;
"B_PERN11"
$PN"DM35"18;
"B_PERP11"
$PN"DK34"17;
"B_PERN10"
$PN"DE35"10;
"B_PERP10"
$PN"DC34"36;
"B_PERN9"
$PN"CV35"11;
"B_PERP9"
$PN"CT34"12;
"B_PERN8"
$PN"CL35"13;
"B_PERP8"
$PN"CJ34"14;
%"TAP"
"1","(-6350,2850)","0","standard","I4";
;
CDS_LIB"standard"
BODY_TYPE"PLUMBING"
HDL_TAP"TRUE";
"B \NAC \NWC"3;
"S \NAC"
BN"9"24;
%"TAP"
"1","(-6550,2950)","0","standard","I5";
;
CDS_LIB"standard"
BODY_TYPE"PLUMBING"
HDL_TAP"TRUE";
"B \NAC \NWC"4;
"S \NAC"
BN"9"23;
%"TAP"
"1","(-6550,3300)","0","standard","I6";
;
CDS_LIB"standard"
BODY_TYPE"PLUMBING"
HDL_TAP"TRUE";
"B \NAC \NWC"4;
"S \NAC"
BN"10"21;
%"TAP"
"1","(-6550,3650)","0","standard","I7";
;
CDS_LIB"standard"
BODY_TYPE"PLUMBING"
HDL_TAP"TRUE";
"B \NAC \NWC"4;
"S \NAC"
BN"11"30;
%"TAP"
"1","(-6350,3200)","0","standard","I8";
;
CDS_LIB"standard"
BODY_TYPE"PLUMBING"
HDL_TAP"TRUE";
"B \NAC \NWC"3;
"S \NAC"
BN"10"22;
%"TAP"
"1","(-6350,3550)","0","standard","I9";
;
CDS_LIB"standard"
BODY_TYPE"PLUMBING"
HDL_TAP"TRUE";
"B \NAC \NWC"3;
"S \NAC"
BN"11"29;
END.
